(kicad_pcb
	(version 20260206)
	(generator "pcbnew")
	(generator_version "10.0")
	(general
		(thickness 1.6)
		(legacy_teardrops no)
	)
	(paper "A4")
	(title_block
		(title "Bryce Canyon_F.DPB_16315-1-OCP.brd")
		(comment 1 "Bryce Canyon / footprints 340-345 of 2223")
	)
	(layers
		(0 "F.Cu" signal "TOP")
		(4 "In1.Cu" signal "L2GND")
		(6 "In2.Cu" signal "L3")
		(8 "In3.Cu" signal "L4GND")
		(10 "In4.Cu" signal "L5")
		(12 "In5.Cu" signal "L6VCC")
		(14 "In6.Cu" signal "L7VCC")
		(16 "In7.Cu" signal "L8")
		(18 "In8.Cu" signal "L9GND")
		(20 "In9.Cu" signal "L10")
		(22 "In10.Cu" signal "L11GND")
		(2 "B.Cu" signal "BOTTOM")
		(9 "F.Adhes" user "F.Adhesive")
		(11 "B.Adhes" user "B.Adhesive")
		(13 "F.Paste" user "Package Geometry/Pastemask Top")
		(15 "B.Paste" user "Package Geometry/Pastemask Bottom")
		(5 "F.SilkS" user "Ref Des/Silkscreen Top")
		(7 "B.SilkS" user "Ref Des/Silkscreen Bottom")
		(1 "F.Mask" user "Board Geometry/Soldermask Top")
		(3 "B.Mask" user "Board Geometry/Soldermask Bottom")
		(17 "Dwgs.User" user "User.Drawings")
		(19 "Cmts.User" user "User.Comments")
		(21 "Eco1.User" user "User.Eco1")
		(23 "Eco2.User" user "User.Eco2")
		(25 "Edge.Cuts" user "Board Geometry/Outline")
		(27 "Margin" user)
		(31 "F.CrtYd" user "Package Geometry/Place Bound Top")
		(29 "B.CrtYd" user "Package Geometry/Place Bound Bottom")
		(35 "F.Fab" user "Ref Des/Assembly Top")
		(33 "B.Fab" user "Ref Des/Assembly Bottom")
	)
	(footprint ""
		(layer "F.Cu")
		(at 258.5212 -290.195 180)
		(property "Reference" "R3"
			(at 0 0 180)
			(layer "F.SilkS")
			(hide yes)
			(effects
				(font
					(size 1.27 1.27)
				)
			)
		)
		(property "Value" "4K7R2F-GP"
			(at 0.064008 -3.993896 180)
			(unlocked yes)
			(layer "F.Fab")
			(hide yes)
			(effects
				(font
					(size 1.016 1.016)
					(thickness 0.1524)
				)
			)
		)
		(property "Device Type" "R402H16"
			(at 0.064008 -5.517896 180)
			(unlocked yes)
			(layer "F.Fab")
			(hide yes)
			(effects
				(font
					(size 1.016 1.016)
					(thickness 0.1524)
				)
			)
		)
		(duplicate_pad_numbers_are_jumpers no)
		(fp_line
			(start 0.508 -0.9398)
			(end -0.508 -0.9398)
			(stroke
				(width 0.1524)
				(type default)
			)
			(layer "F.SilkS")
		)
		(fp_line
			(start -0.508 -0.9398)
			(end -0.508 0.9398)
			(stroke
				(width 0.1524)
				(type default)
			)
			(layer "F.SilkS")
		)
		(fp_rect
			(start -0.508 0.9398)
			(end 0.508 -0.9398)
			(stroke
				(width 0)
				(type default)
			)
			(fill no)
			(layer "F.CrtYd")
		)
		(fp_rect
			(start -0.508 0.9398)
			(end 0.508 -0.9398)
			(stroke
				(width 0)
				(type default)
			)
			(fill no)
			(layer "F.Fab")
		)
		(pad "1" smd custom
			(at 0 -0.4445 180)
			(size 0.1397 0.1397)
			(layers "F.Cu" "F.Mask" "F.Paste")
			(net "P3V3_STBY_A")
			(options
				(clearance outline)
				(anchor circle)
			)
			(primitives
				(gr_poly
					(pts
						(arc
							(start -0.1778 -0.2794)
							(mid -0.249642 -0.249642)
							(end -0.2794 -0.1778)
						)
						(arc
							(start -0.2794 0.1778)
							(mid -0.249642 0.249642)
							(end -0.1778 0.2794)
						)
						(arc
							(start 0.1778 0.2794)
							(mid 0.249642 0.249642)
							(end 0.2794 0.1778)
						)
						(arc
							(start 0.2794 -0.1778)
							(mid 0.249642 -0.249642)
							(end 0.1778 -0.2794)
						)
					)
					(width 0)
					(fill yes)
				)
			)
		)
		(pad "2" smd custom
			(at 0 0.4445 180)
			(size 0.1397 0.1397)
			(layers "F.Cu" "F.Mask" "F.Paste")
			(net "EEPROM_A2")
			(options
				(clearance outline)
				(anchor circle)
			)
			(primitives
				(gr_poly
					(pts
						(arc
							(start -0.1778 -0.2794)
							(mid -0.249642 -0.249642)
							(end -0.2794 -0.1778)
						)
						(arc
							(start -0.2794 0.1778)
							(mid -0.249642 0.249642)
							(end -0.1778 0.2794)
						)
						(arc
							(start 0.1778 0.2794)
							(mid 0.249642 0.249642)
							(end 0.2794 0.1778)
						)
						(arc
							(start 0.2794 -0.1778)
							(mid 0.249642 -0.249642)
							(end 0.1778 -0.2794)
						)
					)
					(width 0)
					(fill yes)
				)
			)
		)
	)
	(footprint ""
		(layer "F.Cu")
		(at 83.784948 -285.285942 180)
		(property "Reference" "Q12"
			(at 0 0 180)
			(layer "F.SilkS")
			(hide yes)
			(effects
				(font
					(size 1.27 1.27)
				)
			)
		)
		(property "Value" "AO4406AL-GP"
			(at -3.707384 -1.5367 180)
			(unlocked yes)
			(layer "F.Fab")
			(hide yes)
			(effects
				(font
					(size 1.016 1.016)
					(thickness 0.1524)
				)
			)
		)
		(property "Device Type" "SOIC8H69"
			(at -3.707384 -3.0607 180)
			(unlocked yes)
			(layer "F.Fab")
			(hide yes)
			(effects
				(font
					(size 1.016 1.016)
					(thickness 0.1524)
				)
			)
		)
		(duplicate_pad_numbers_are_jumpers no)
		(fp_line
			(start 2.1336 1.4224)
			(end 2.1336 -1.4224)
			(stroke
				(width 0.1524)
				(type default)
			)
			(layer "F.SilkS")
		)
		(fp_line
			(start 2.1336 -1.4224)
			(end -2.7432 -1.4224)
			(stroke
				(width 0.1524)
				(type default)
			)
			(layer "F.SilkS")
		)
		(fp_line
			(start -2.1844 -0.0508)
			(end -2.7178 0.508)
			(stroke
				(width 0.1524)
				(type default)
			)
			(layer "F.SilkS")
		)
		(fp_line
			(start -2.6289 3.4417)
			(end -2.6289 1.4732)
			(stroke
				(width 0.381)
				(type default)
			)
			(layer "F.SilkS")
		)
		(fp_line
			(start -2.7178 -0.508)
			(end -2.1844 -0.0508)
			(stroke
				(width 0.1524)
				(type default)
			)
			(layer "F.SilkS")
		)
		(fp_line
			(start -2.7432 1.4224)
			(end 2.1336 1.4224)
			(stroke
				(width 0.1524)
				(type default)
			)
			(layer "F.SilkS")
		)
		(fp_line
			(start -2.7432 1.4224)
			(end -2.6416 1.4224)
			(stroke
				(width 0.1524)
				(type default)
			)
			(layer "F.SilkS")
		)
		(fp_line
			(start -2.7432 -1.4224)
			(end -2.7432 1.4224)
			(stroke
				(width 0.1524)
				(type default)
			)
			(layer "F.SilkS")
		)
		(fp_poly
			(pts
				(xy -2.2098 -1.4224) (xy -2.2098 1.4224) (xy 2.2098 1.4224) (xy 2.2098 -1.4224)
			)
			(stroke
				(width 0)
				(type default)
			)
			(fill yes)
			(layer "F.SilkS")
		)
		(fp_rect
			(start -2.450084 2.999994)
			(end 2.450084 -2.999994)
			(stroke
				(width 0)
				(type default)
			)
			(fill no)
			(layer "F.CrtYd")
		)
		(fp_poly
			(pts
				(xy -2.8194 3.6322) (xy -2.8194 -3.6322) (xy 2.8194 -3.6322) (xy 2.8194 1.18364) (xy 2.450084 1.18364)
				(xy 2.450084 -2.999994) (xy -2.450084 -2.999994) (xy -2.450084 2.999994) (xy 2.450084 2.999994)
				(xy 2.450084 1.18618) (xy 2.8194 1.18618) (xy 2.8194 3.6322)
			)
			(stroke
				(width 0)
				(type default)
			)
			(fill no)
			(layer "F.CrtYd")
		)
		(fp_rect
			(start -2.8194 3.6322)
			(end 2.8194 -3.6322)
			(stroke
				(width 0)
				(type default)
			)
			(fill no)
			(layer "F.Fab")
		)
		(pad "1" smd rect
			(at -1.905 2.54 180)
			(size 0.635 1.651)
			(layers "F.Cu" "F.Mask" "F.Paste")
			(net "P5V_HDD2")
		)
		(pad "2" smd rect
			(at -0.635 2.54 180)
			(size 0.635 1.651)
			(layers "F.Cu" "F.Mask" "F.Paste")
			(net "P5V_HDD2")
		)
		(pad "3" smd rect
			(at 0.635 2.54 180)
			(size 0.635 1.651)
			(layers "F.Cu" "F.Mask" "F.Paste")
			(net "P5V_HDD2")
		)
		(pad "4" smd rect
			(at 1.905 2.54 180)
			(size 0.635 1.651)
			(layers "F.Cu" "F.Mask" "F.Paste")
			(net "SW_HDD_P2")
		)
		(pad "5" smd rect
			(at 1.905 -2.54 180)
			(size 0.635 1.651)
			(layers "F.Cu" "F.Mask" "F.Paste")
			(net "P5V_A_1")
		)
		(pad "6" smd rect
			(at 0.635 -2.54 180)
			(size 0.635 1.651)
			(layers "F.Cu" "F.Mask" "F.Paste")
			(net "P5V_A_1")
		)
		(pad "7" smd rect
			(at -0.635 -2.54 180)
			(size 0.635 1.651)
			(layers "F.Cu" "F.Mask" "F.Paste")
			(net "P5V_A_1")
		)
		(pad "8" smd rect
			(at -1.905 -2.54 180)
			(size 0.635 1.651)
			(layers "F.Cu" "F.Mask" "F.Paste")
			(net "P5V_A_1")
		)
	)
	(footprint ""
		(layer "F.Cu")
		(at 222.619316 -116.728748 -90)
		(property "Reference" "R157"
			(at 0 0 270)
			(layer "F.SilkS")
			(hide yes)
			(effects
				(font
					(size 1.27 1.27)
				)
			)
		)
		(property "Value" "0R2J-2-GP"
			(at 0.064008 -3.993896 270)
			(unlocked yes)
			(layer "F.Fab")
			(hide yes)
			(effects
				(font
					(size 1.016 1.016)
					(thickness 0.1524)
				)
			)
		)
		(property "Device Type" "R402H16"
			(at 0.064008 -5.517896 270)
			(unlocked yes)
			(layer "F.Fab")
			(hide yes)
			(effects
				(font
					(size 1.016 1.016)
					(thickness 0.1524)
				)
			)
		)
		(duplicate_pad_numbers_are_jumpers no)
		(fp_line
			(start -0.508 -0.9398)
			(end -0.508 0.9398)
			(stroke
				(width 0.1524)
				(type default)
			)
			(layer "F.SilkS")
		)
		(fp_line
			(start 0.508 -0.9398)
			(end -0.508 -0.9398)
			(stroke
				(width 0.1524)
				(type default)
			)
			(layer "F.SilkS")
		)
		(fp_rect
			(start -0.508 0.9398)
			(end 0.508 -0.9398)
			(stroke
				(width 0)
				(type default)
			)
			(fill no)
			(layer "F.CrtYd")
		)
		(fp_rect
			(start -0.508 0.9398)
			(end 0.508 -0.9398)
			(stroke
				(width 0)
				(type default)
			)
			(fill no)
			(layer "F.Fab")
		)
		(pad "1" smd custom
			(at 0 -0.4445 270)
			(size 0.1397 0.1397)
			(layers "F.Cu" "F.Mask" "F.Paste")
			(net "SLOT3_SVR_ID0_GPIO3")
			(options
				(clearance outline)
				(anchor circle)
			)
			(primitives
				(gr_poly
					(pts
						(arc
							(start -0.1778 -0.2794)
							(mid -0.249642 -0.249642)
							(end -0.2794 -0.1778)
						)
						(arc
							(start -0.2794 0.1778)
							(mid -0.249642 0.249642)
							(end -0.1778 0.2794)
						)
						(arc
							(start 0.1778 0.2794)
							(mid 0.249642 0.249642)
							(end 0.2794 0.1778)
						)
						(arc
							(start 0.2794 -0.1778)
							(mid 0.249642 -0.249642)
							(end 0.1778 -0.2794)
						)
					)
					(width 0)
					(fill yes)
				)
			)
		)
		(pad "2" smd custom
			(at 0 0.4445 270)
			(size 0.1397 0.1397)
			(layers "F.Cu" "F.Mask" "F.Paste")
			(net "COMP_A_TO_BMC_A_RESET_N")
			(options
				(clearance outline)
				(anchor circle)
			)
			(primitives
				(gr_poly
					(pts
						(arc
							(start -0.1778 -0.2794)
							(mid -0.249642 -0.249642)
							(end -0.2794 -0.1778)
						)
						(arc
							(start -0.2794 0.1778)
							(mid -0.249642 0.249642)
							(end -0.1778 0.2794)
						)
						(arc
							(start 0.1778 0.2794)
							(mid 0.249642 0.249642)
							(end 0.2794 0.1778)
						)
						(arc
							(start 0.2794 -0.1778)
							(mid 0.249642 -0.249642)
							(end 0.1778 -0.2794)
						)
					)
					(width 0)
					(fill yes)
				)
			)
		)
	)
	(footprint ""
		(layer "F.Cu")
		(at 246.992902 -393.107164)
		(property "Reference" "R1171"
			(at 0 0 0)
			(layer "F.SilkS")
			(hide yes)
			(effects
				(font
					(size 1.27 1.27)
				)
			)
		)
		(property "Value" "5K1R2F-3-GP"
			(at 0.064008 -3.993896 0)
			(unlocked yes)
			(layer "F.Fab")
			(hide yes)
			(effects
				(font
					(size 1.016 1.016)
					(thickness 0.1524)
				)
			)
		)
		(property "Device Type" "R402H16"
			(at 0.064008 -5.517896 0)
			(unlocked yes)
			(layer "F.Fab")
			(hide yes)
			(effects
				(font
					(size 1.016 1.016)
					(thickness 0.1524)
				)
			)
		)
		(duplicate_pad_numbers_are_jumpers no)
		(fp_line
			(start -0.508 -0.9398)
			(end -0.508 0.9398)
			(stroke
				(width 0.1524)
				(type default)
			)
			(layer "F.SilkS")
		)
		(fp_line
			(start 0.508 -0.9398)
			(end -0.508 -0.9398)
			(stroke
				(width 0.1524)
				(type default)
			)
			(layer "F.SilkS")
		)
		(fp_rect
			(start -0.508 0.9398)
			(end 0.508 -0.9398)
			(stroke
				(width 0)
				(type default)
			)
			(fill no)
			(layer "F.CrtYd")
		)
		(fp_rect
			(start -0.508 0.9398)
			(end 0.508 -0.9398)
			(stroke
				(width 0)
				(type default)
			)
			(fill no)
			(layer "F.Fab")
		)
		(pad "1" smd custom
			(at 0 -0.4445)
			(size 0.1397 0.1397)
			(layers "F.Cu" "F.Mask" "F.Paste")
			(net "MB3_CM_UV_R")
			(options
				(clearance outline)
				(anchor circle)
			)
			(primitives
				(gr_poly
					(pts
						(arc
							(start -0.1778 -0.2794)
							(mid -0.249642 -0.249642)
							(end -0.2794 -0.1778)
						)
						(arc
							(start -0.2794 0.1778)
							(mid -0.249642 0.249642)
							(end -0.1778 0.2794)
						)
						(arc
							(start 0.1778 0.2794)
							(mid 0.249642 0.249642)
							(end 0.2794 0.1778)
						)
						(arc
							(start 0.2794 -0.1778)
							(mid 0.249642 -0.249642)
							(end 0.1778 -0.2794)
						)
					)
					(width 0)
					(fill yes)
				)
			)
		)
		(pad "2" smd custom
			(at 0 0.4445)
			(size 0.1397 0.1397)
			(layers "F.Cu" "F.Mask" "F.Paste")
			(net "AGND_CURRENT_DPB")
			(options
				(clearance outline)
				(anchor circle)
			)
			(primitives
				(gr_poly
					(pts
						(arc
							(start -0.1778 -0.2794)
							(mid -0.249642 -0.249642)
							(end -0.2794 -0.1778)
						)
						(arc
							(start -0.2794 0.1778)
							(mid -0.249642 0.249642)
							(end -0.1778 0.2794)
						)
						(arc
							(start 0.1778 0.2794)
							(mid 0.249642 0.249642)
							(end 0.2794 0.1778)
						)
						(arc
							(start 0.2794 -0.1778)
							(mid 0.249642 -0.249642)
							(end 0.1778 -0.2794)
						)
					)
					(width 0)
					(fill yes)
				)
			)
		)
	)
	(footprint ""
		(layer "F.Cu")
		(at 158.663386 -44.219368 90)
		(property "Reference" "C402"
			(at 0 0 90)
			(layer "F.SilkS")
			(hide yes)
			(effects
				(font
					(size 1.27 1.27)
				)
			)
		)
		(property "Value" "SCD01U16V1KX-GP"
			(at -2.8321 -1.7399 90)
			(unlocked yes)
			(layer "F.Fab")
			(hide yes)
			(effects
				(font
					(size 1.016 1.016)
					(thickness 0.1524)
				)
			)
		)
		(property "Device Type" "C0201H13"
			(at -2.8321 -3.2639 90)
			(unlocked yes)
			(layer "F.Fab")
			(hide yes)
			(effects
				(font
					(size 1.016 1.016)
					(thickness 0.1524)
				)
			)
		)
		(duplicate_pad_numbers_are_jumpers no)
		(fp_rect
			(start -0.2794 0.6477)
			(end 0.2794 -0.6477)
			(stroke
				(width 0)
				(type default)
			)
			(fill no)
			(layer "F.CrtYd")
		)
		(fp_rect
			(start -0.2794 0.6477)
			(end 0.2794 -0.6477)
			(stroke
				(width 0)
				(type default)
			)
			(fill no)
			(layer "F.Fab")
		)
		(pad "1" smd custom
			(at 0 -0.2794 90)
			(size 0.0762 0.0762)
			(layers "F.Cu" "F.Mask" "F.Paste")
			(net "SAS_HDD_RX_N28")
			(options
				(clearance outline)
				(anchor circle)
			)
			(primitives
				(gr_poly
					(pts
						(arc
							(start 0.1524 -0.127)
							(mid 0.137521 -0.162921)
							(end 0.1016 -0.1778)
						)
						(arc
							(start -0.1016 -0.1778)
							(mid -0.137521 -0.162921)
							(end -0.1524 -0.127)
						)
						(arc
							(start -0.1524 0.127)
							(mid -0.137521 0.162921)
							(end -0.1016 0.1778)
						)
						(arc
							(start 0.1016 0.1778)
							(mid 0.137521 0.162921)
							(end 0.1524 0.127)
						)
					)
					(width 0)
					(fill yes)
				)
			)
		)
		(pad "2" smd custom
			(at 0 0.2794 90)
			(size 0.0762 0.0762)
			(layers "F.Cu" "F.Mask" "F.Paste")
			(net "PHY_SCC_A_TO_DRV_A_28_DN")
			(options
				(clearance outline)
				(anchor circle)
			)
			(primitives
				(gr_poly
					(pts
						(arc
							(start 0.1524 -0.127)
							(mid 0.137521 -0.162921)
							(end 0.1016 -0.1778)
						)
						(arc
							(start -0.1016 -0.1778)
							(mid -0.137521 -0.162921)
							(end -0.1524 -0.127)
						)
						(arc
							(start -0.1524 0.127)
							(mid -0.137521 0.162921)
							(end -0.1016 0.1778)
						)
						(arc
							(start 0.1016 0.1778)
							(mid 0.137521 0.162921)
							(end 0.1524 0.127)
						)
					)
					(width 0)
					(fill yes)
				)
			)
		)
	)
	(footprint ""
		(layer "F.Cu")
		(at 38.05682 -188.915294)
		(property "Reference" "Q224"
			(at 0 0 0)
			(layer "F.SilkS")
			(hide yes)
			(effects
				(font
					(size 1.27 1.27)
				)
			)
		)
		(property "Value" "2N7002K-2-GP"
			(at 0.127 -8.9662 0)
			(unlocked yes)
			(layer "F.Fab")
			(hide yes)
			(effects
				(font
					(size 1.016 1.016)
					(thickness 0.1524)
				)
			)
		)
		(property "Device Type" "SOT23DGS2D4H44"
			(at 0.127 -10.4902 0)
			(unlocked yes)
			(layer "F.Fab")
			(hide yes)
			(effects
				(font
					(size 1.016 1.016)
					(thickness 0.1524)
				)
			)
		)
		(duplicate_pad_numbers_are_jumpers no)
		(fp_line
			(start -1.651 -1.778)
			(end -1.651 1.778)
			(stroke
				(width 0.1524)
				(type default)
			)
			(layer "F.SilkS")
		)
		(fp_line
			(start -1.651 1.778)
			(end 1.651 1.778)
			(stroke
				(width 0.1524)
				(type default)
			)
			(layer "F.SilkS")
		)
		(fp_line
			(start 1.651 -1.778)
			(end -1.651 -1.778)
			(stroke
				(width 0.1524)
				(type default)
			)
			(layer "F.SilkS")
		)
		(fp_line
			(start 1.651 1.778)
			(end 1.651 -1.778)
			(stroke
				(width 0.1524)
				(type default)
			)
			(layer "F.SilkS")
		)
		(fp_poly
			(pts
				(xy -1.778 1.8796) (xy -1.778 -1.8796) (xy 1.778 -1.8796) (xy 1.778 1.8796)
			)
			(stroke
				(width 0)
				(type default)
			)
			(fill no)
			(layer "F.CrtYd")
		)
		(fp_poly
			(pts
				(xy -1.778 1.8796) (xy -1.778 -1.8796) (xy 1.778 -1.8796) (xy 1.778 1.8796)
			)
			(stroke
				(width 0)
				(type default)
			)
			(fill no)
			(layer "F.Fab")
		)
		(pad "D" smd custom
			(at 0 -0.9525)
			(size 0.1905 0.1905)
			(layers "F.Cu" "F.Mask" "F.Paste")
			(net "FLT_HDD1_N")
			(options
				(clearance outline)
				(anchor circle)
			)
			(primitives
				(gr_poly
					(pts
						(arc
							(start -0.1778 0.5715)
							(mid -0.321484 0.511984)
							(end -0.381 0.3683)
						)
						(arc
							(start -0.381 -0.3683)
							(mid -0.321484 -0.511984)
							(end -0.1778 -0.5715)
						)
						(arc
							(start 0.1778 -0.5715)
							(mid 0.321484 -0.511984)
							(end 0.381 -0.3683)
						)
						(arc
							(start 0.381 0.3683)
							(mid 0.321484 0.511984)
							(end 0.1778 0.5715)
						)
					)
					(width 0)
					(fill yes)
				)
			)
		)
		(pad "G" smd custom
			(at -0.98425 0.9525)
			(size 0.1905 0.1905)
			(layers "F.Cu" "F.Mask" "F.Paste")
			(net "DRIVE_A_1_FLT_LED")
			(options
				(clearance outline)
				(anchor circle)
			)
			(primitives
				(gr_poly
					(pts
						(arc
							(start -0.1778 0.5715)
							(mid -0.321484 0.511984)
							(end -0.381 0.3683)
						)
						(arc
							(start -0.381 -0.3683)
							(mid -0.321484 -0.511984)
							(end -0.1778 -0.5715)
						)
						(arc
							(start 0.1778 -0.5715)
							(mid 0.321484 -0.511984)
							(end 0.381 -0.3683)
						)
						(arc
							(start 0.381 0.3683)
							(mid 0.321484 0.511984)
							(end 0.1778 0.5715)
						)
					)
					(width 0)
					(fill yes)
				)
			)
		)
		(pad "S" smd custom
			(at 0.98425 0.9525)
			(size 0.1905 0.1905)
			(layers "F.Cu" "F.Mask" "F.Paste")
			(net "GND")
			(options
				(clearance outline)
				(anchor circle)
			)
			(primitives
				(gr_poly
					(pts
						(arc
							(start -0.1778 0.5715)
							(mid -0.321484 0.511984)
							(end -0.381 0.3683)
						)
						(arc
							(start -0.381 -0.3683)
							(mid -0.321484 -0.511984)
							(end -0.1778 -0.5715)
						)
						(arc
							(start 0.1778 -0.5715)
							(mid 0.321484 -0.511984)
							(end 0.381 -0.3683)
						)
						(arc
							(start 0.381 0.3683)
							(mid 0.321484 0.511984)
							(end 0.1778 0.5715)
						)
					)
					(width 0)
					(fill yes)
				)
			)
		)
	)
)
